(kicad_pcb
	(version 20260206)
	(generator "pcbnew")
	(generator_version "10.0")
	(general
		(thickness 1.6)
		(legacy_teardrops no)
	)
	(paper "A4")
	(title_block
		(title "03242023_DA0F0TMBIJ0_F0T_Motherboard_J_brd_V01_OCP.brd")
		(comment 1 "Grand Teton / footprint 663 of 6105 (J21), pads 225-291 of 291")
	)
	(layers
		(0 "F.Cu" signal "TOP")
		(4 "In1.Cu" signal "GND")
		(6 "In2.Cu" signal "IN1")
		(8 "In3.Cu" signal "GND1")
		(10 "In4.Cu" signal "IN2")
		(12 "In5.Cu" signal "GND2")
		(14 "In6.Cu" signal "IN3")
		(16 "In7.Cu" signal "GND3")
		(18 "In8.Cu" signal "VCC")
		(20 "In9.Cu" signal "VCC1")
		(22 "In10.Cu" signal "GND4")
		(24 "In11.Cu" signal "IN4")
		(26 "In12.Cu" signal "GND5")
		(28 "In13.Cu" signal "IN5")
		(30 "In14.Cu" signal "GND6")
		(32 "In15.Cu" signal "IN6")
		(34 "In16.Cu" signal "GND7")
		(2 "B.Cu" signal "BOTTOM")
		(9 "F.Adhes" user "F.Adhesive")
		(11 "B.Adhes" user "B.Adhesive")
		(13 "F.Paste" user "Package Geometry/Pastemask Top")
		(15 "B.Paste" user "Package Geometry/Pastemask Bottom")
		(5 "F.SilkS" user "Ref Des/Silkscreen Top")
		(7 "B.SilkS" user "Ref Des/Silkscreen Bottom")
		(1 "F.Mask" user "Board Geometry/Soldermask Top")
		(3 "B.Mask" user "Board Geometry/Soldermask Bottom")
		(17 "Dwgs.User" user "User.Drawings")
		(19 "Cmts.User" user "User.Comments")
		(21 "Eco1.User" user "User.Eco1")
		(23 "Eco2.User" user "User.Eco2")
		(25 "Edge.Cuts" user "Board Geometry/Outline")
		(27 "Margin" user)
		(31 "F.CrtYd" user "Package Geometry/Place Bound Top")
		(29 "B.CrtYd" user "Package Geometry/Place Bound Bottom")
		(35 "F.Fab" user "Ref Des/Assembly Top")
		(33 "B.Fab" user "Ref Des/Assembly Bottom")
	)
	(footprint ""
		(layer "F.Cu")
		(at 25.27808 -258.091686)
		(property "Reference" "J21"
			(at -0.325882 -81.821274 0)
			(unlocked yes)
			(layer "F.SilkS")
			(effects
				(font
					(size 0.7874 0.5842)
					(thickness 0.1524)
				)
				(justify left)
			)
		)
		(property "Value" ""
			(at 0 0 0)
			(layer "F.Fab")
			(effects
				(font
					(size 1.27 1.27)
				)
			)
		)
		(duplicate_pad_numbers_are_jumpers no)
		(pad "225" smd rect
			(at 2.050034 9.774936 270)
			(size 0.519938 1.4986)
			(layers "F.Cu" "F.Mask" "F.Paste")
			(net "M_C_CPU1_SB_CA<5>")
		)
		(pad "226" smd rect
			(at 2.050034 10.625074 270)
			(size 0.519938 1.4986)
			(layers "F.Cu" "F.Mask" "F.Paste")
			(net "GND")
		)
		(pad "227" smd rect
			(at 2.050034 11.474958 270)
			(size 0.519938 1.4986)
			(layers "F.Cu" "F.Mask" "F.Paste")
			(net "M_C_CPU1_SB_PAR")
		)
		(pad "228" smd rect
			(at 2.050034 12.325096 270)
			(size 0.519938 1.4986)
			(layers "F.Cu" "F.Mask" "F.Paste")
			(net "GND")
		)
		(pad "229" smd rect
			(at 2.050034 13.17498 270)
			(size 0.519938 1.4986)
			(layers "F.Cu" "F.Mask" "F.Paste")
			(net "M_C_CPU1_SB_CS_N<1>")
		)
		(pad "230" smd rect
			(at 2.050034 14.025118 270)
			(size 0.519938 1.4986)
			(layers "F.Cu" "F.Mask" "F.Paste")
			(net "GND")
		)
		(pad "231" smd rect
			(at 2.050034 14.875002 270)
			(size 0.519938 1.4986)
			(layers "F.Cu" "F.Mask" "F.Paste")
			(net "TP_CHC_CPU1_DIMM1_FRU_5")
		)
		(pad "232" smd rect
			(at 2.050034 15.724886 270)
			(size 0.519938 1.4986)
			(layers "F.Cu" "F.Mask" "F.Paste")
			(net "TP_CHC_CPU1_DIMM1_FRU_6")
		)
		(pad "233" smd rect
			(at 2.050034 16.575024 270)
			(size 0.519938 1.4986)
			(layers "F.Cu" "F.Mask" "F.Paste")
			(net "GND")
		)
		(pad "234" smd rect
			(at 2.050034 17.424908 270)
			(size 0.519938 1.4986)
			(layers "F.Cu" "F.Mask" "F.Paste")
			(net "M_C_CPU1_SB_CB<6>")
		)
		(pad "235" smd rect
			(at 2.050034 18.275046 270)
			(size 0.519938 1.4986)
			(layers "F.Cu" "F.Mask" "F.Paste")
			(net "GND")
		)
		(pad "236" smd rect
			(at 2.050034 19.12493 270)
			(size 0.519938 1.4986)
			(layers "F.Cu" "F.Mask" "F.Paste")
			(net "M_C_CPU1_SB_CB<7>")
		)
		(pad "237" smd rect
			(at 2.050034 19.975068 270)
			(size 0.519938 1.4986)
			(layers "F.Cu" "F.Mask" "F.Paste")
			(net "GND")
		)
		(pad "238" smd rect
			(at 2.050034 20.824952 270)
			(size 0.519938 1.4986)
			(layers "F.Cu" "F.Mask" "F.Paste")
			(net "M_C_CPU1_SB_DQS_DN<4>")
		)
		(pad "239" smd rect
			(at 2.050034 21.67509 270)
			(size 0.519938 1.4986)
			(layers "F.Cu" "F.Mask" "F.Paste")
			(net "M_C_CPU1_SB_DQS_DP<4>")
		)
		(pad "240" smd rect
			(at 2.050034 22.524974 270)
			(size 0.519938 1.4986)
			(layers "F.Cu" "F.Mask" "F.Paste")
			(net "GND")
		)
		(pad "241" smd rect
			(at 2.050034 23.375112 270)
			(size 0.519938 1.4986)
			(layers "F.Cu" "F.Mask" "F.Paste")
			(net "M_C_CPU1_SB_CB<2>")
		)
		(pad "242" smd rect
			(at 2.050034 24.224996 270)
			(size 0.519938 1.4986)
			(layers "F.Cu" "F.Mask" "F.Paste")
			(net "GND")
		)
		(pad "243" smd rect
			(at 2.050034 25.07488 270)
			(size 0.519938 1.4986)
			(layers "F.Cu" "F.Mask" "F.Paste")
			(net "M_C_CPU1_SB_CB<3>")
		)
		(pad "244" smd rect
			(at 2.050034 25.925018 270)
			(size 0.519938 1.4986)
			(layers "F.Cu" "F.Mask" "F.Paste")
			(net "GND")
		)
		(pad "245" smd rect
			(at 2.050034 26.774902 270)
			(size 0.519938 1.4986)
			(layers "F.Cu" "F.Mask" "F.Paste")
			(net "M_C_CPU1_SB_DQ<2>")
		)
		(pad "246" smd rect
			(at 2.050034 27.62504 270)
			(size 0.519938 1.4986)
			(layers "F.Cu" "F.Mask" "F.Paste")
			(net "GND")
		)
		(pad "247" smd rect
			(at 2.050034 28.474924 270)
			(size 0.519938 1.4986)
			(layers "F.Cu" "F.Mask" "F.Paste")
			(net "M_C_CPU1_SB_DQ<3>")
		)
		(pad "248" smd rect
			(at 2.050034 29.325062 270)
			(size 0.519938 1.4986)
			(layers "F.Cu" "F.Mask" "F.Paste")
			(net "GND")
		)
		(pad "249" smd rect
			(at 2.050034 30.174946 270)
			(size 0.519938 1.4986)
			(layers "F.Cu" "F.Mask" "F.Paste")
			(net "M_C_CPU1_SB_DQS_DN<5>")
		)
		(pad "250" smd rect
			(at 2.050034 31.025084 270)
			(size 0.519938 1.4986)
			(layers "F.Cu" "F.Mask" "F.Paste")
			(net "M_C_CPU1_SB_DQS_DP<5>")
		)
		(pad "251" smd rect
			(at 2.050034 31.874968 270)
			(size 0.519938 1.4986)
			(layers "F.Cu" "F.Mask" "F.Paste")
			(net "GND")
		)
		(pad "252" smd rect
			(at 2.050034 32.725106 270)
			(size 0.519938 1.4986)
			(layers "F.Cu" "F.Mask" "F.Paste")
			(net "M_C_CPU1_SB_DQ<6>")
		)
		(pad "253" smd rect
			(at 2.050034 33.57499 270)
			(size 0.519938 1.4986)
			(layers "F.Cu" "F.Mask" "F.Paste")
			(net "GND")
		)
		(pad "254" smd rect
			(at 2.050034 34.425128 270)
			(size 0.519938 1.4986)
			(layers "F.Cu" "F.Mask" "F.Paste")
			(net "M_C_CPU1_SB_DQ<7>")
		)
		(pad "255" smd rect
			(at 2.050034 35.275012 270)
			(size 0.519938 1.4986)
			(layers "F.Cu" "F.Mask" "F.Paste")
			(net "GND")
		)
		(pad "256" smd rect
			(at 2.050034 36.124896 270)
			(size 0.519938 1.4986)
			(layers "F.Cu" "F.Mask" "F.Paste")
			(net "M_C_CPU1_SB_DQ<10>")
		)
		(pad "257" smd rect
			(at 2.050034 36.975034 270)
			(size 0.519938 1.4986)
			(layers "F.Cu" "F.Mask" "F.Paste")
			(net "GND")
		)
		(pad "258" smd rect
			(at 2.050034 37.824918 270)
			(size 0.519938 1.4986)
			(layers "F.Cu" "F.Mask" "F.Paste")
			(net "M_C_CPU1_SB_DQ<11>")
		)
		(pad "259" smd rect
			(at 2.050034 38.675056 270)
			(size 0.519938 1.4986)
			(layers "F.Cu" "F.Mask" "F.Paste")
			(net "GND")
		)
		(pad "260" smd rect
			(at 2.050034 39.52494 270)
			(size 0.519938 1.4986)
			(layers "F.Cu" "F.Mask" "F.Paste")
			(net "M_C_CPU1_SB_DQS_DN<6>")
		)
		(pad "261" smd rect
			(at 2.050034 40.375078 270)
			(size 0.519938 1.4986)
			(layers "F.Cu" "F.Mask" "F.Paste")
			(net "M_C_CPU1_SB_DQS_DP<6>")
		)
		(pad "262" smd rect
			(at 2.050034 41.224962 270)
			(size 0.519938 1.4986)
			(layers "F.Cu" "F.Mask" "F.Paste")
			(net "GND")
		)
		(pad "263" smd rect
			(at 2.050034 42.0751 270)
			(size 0.519938 1.4986)
			(layers "F.Cu" "F.Mask" "F.Paste")
			(net "M_C_CPU1_SB_DQ<14>")
		)
		(pad "264" smd rect
			(at 2.050034 42.924984 270)
			(size 0.519938 1.4986)
			(layers "F.Cu" "F.Mask" "F.Paste")
			(net "GND")
		)
		(pad "265" smd rect
			(at 2.050034 43.775122 270)
			(size 0.519938 1.4986)
			(layers "F.Cu" "F.Mask" "F.Paste")
			(net "M_C_CPU1_SB_DQ<15>")
		)
		(pad "266" smd rect
			(at 2.050034 44.625006 270)
			(size 0.519938 1.4986)
			(layers "F.Cu" "F.Mask" "F.Paste")
			(net "GND")
		)
		(pad "267" smd rect
			(at 2.050034 45.47489 270)
			(size 0.519938 1.4986)
			(layers "F.Cu" "F.Mask" "F.Paste")
			(net "M_C_CPU1_SB_DQ<18>")
		)
		(pad "268" smd rect
			(at 2.050034 46.325028 270)
			(size 0.519938 1.4986)
			(layers "F.Cu" "F.Mask" "F.Paste")
			(net "GND")
		)
		(pad "269" smd rect
			(at 2.050034 47.174912 270)
			(size 0.519938 1.4986)
			(layers "F.Cu" "F.Mask" "F.Paste")
			(net "M_C_CPU1_SB_DQ<19>")
		)
		(pad "270" smd rect
			(at 2.050034 48.02505 270)
			(size 0.519938 1.4986)
			(layers "F.Cu" "F.Mask" "F.Paste")
			(net "GND")
		)
		(pad "271" smd rect
			(at 2.050034 48.874934 270)
			(size 0.519938 1.4986)
			(layers "F.Cu" "F.Mask" "F.Paste")
			(net "M_C_CPU1_SB_DQS_DN<7>")
		)
		(pad "272" smd rect
			(at 2.050034 49.725072 270)
			(size 0.519938 1.4986)
			(layers "F.Cu" "F.Mask" "F.Paste")
			(net "M_C_CPU1_SB_DQS_DP<7>")
		)
		(pad "273" smd rect
			(at 2.050034 50.574956 270)
			(size 0.519938 1.4986)
			(layers "F.Cu" "F.Mask" "F.Paste")
			(net "GND")
		)
		(pad "274" smd rect
			(at 2.050034 51.425094 270)
			(size 0.519938 1.4986)
			(layers "F.Cu" "F.Mask" "F.Paste")
			(net "M_C_CPU1_SB_DQ<22>")
		)
		(pad "275" smd rect
			(at 2.050034 52.274978 270)
			(size 0.519938 1.4986)
			(layers "F.Cu" "F.Mask" "F.Paste")
			(net "GND")
		)
		(pad "276" smd rect
			(at 2.050034 53.125116 270)
			(size 0.519938 1.4986)
			(layers "F.Cu" "F.Mask" "F.Paste")
			(net "M_C_CPU1_SB_DQ<23>")
		)
		(pad "277" smd rect
			(at 2.050034 53.975 270)
			(size 0.519938 1.4986)
			(layers "F.Cu" "F.Mask" "F.Paste")
			(net "GND")
		)
		(pad "278" smd rect
			(at 2.050034 54.824884 270)
			(size 0.519938 1.4986)
			(layers "F.Cu" "F.Mask" "F.Paste")
			(net "M_C_CPU1_SB_DQ<26>")
		)
		(pad "279" smd rect
			(at 2.050034 55.675022 270)
			(size 0.519938 1.4986)
			(layers "F.Cu" "F.Mask" "F.Paste")
			(net "GND")
		)
		(pad "280" smd rect
			(at 2.050034 56.524906 270)
			(size 0.519938 1.4986)
			(layers "F.Cu" "F.Mask" "F.Paste")
			(net "M_C_CPU1_SB_DQ<27>")
		)
		(pad "281" smd rect
			(at 2.050034 57.375044 270)
			(size 0.519938 1.4986)
			(layers "F.Cu" "F.Mask" "F.Paste")
			(net "GND")
		)
		(pad "282" smd rect
			(at 2.050034 58.224928 270)
			(size 0.519938 1.4986)
			(layers "F.Cu" "F.Mask" "F.Paste")
			(net "M_C_CPU1_SB_DQS_DN<8>")
		)
		(pad "283" smd rect
			(at 2.050034 59.075066 270)
			(size 0.519938 1.4986)
			(layers "F.Cu" "F.Mask" "F.Paste")
			(net "M_C_CPU1_SB_DQS_DP<8>")
		)
		(pad "284" smd rect
			(at 2.050034 59.92495 270)
			(size 0.519938 1.4986)
			(layers "F.Cu" "F.Mask" "F.Paste")
			(net "GND")
		)
		(pad "285" smd rect
			(at 2.050034 60.775088 270)
			(size 0.519938 1.4986)
			(layers "F.Cu" "F.Mask" "F.Paste")
			(net "M_C_CPU1_SB_DQ<30>")
		)
		(pad "286" smd rect
			(at 2.050034 61.624972 270)
			(size 0.519938 1.4986)
			(layers "F.Cu" "F.Mask" "F.Paste")
			(net "GND")
		)
		(pad "287" smd rect
			(at 2.050034 62.47511 270)
			(size 0.519938 1.4986)
			(layers "F.Cu" "F.Mask" "F.Paste")
			(net "M_C_CPU1_SB_DQ<31>")
		)
		(pad "288" smd rect
			(at 2.050034 63.324994 270)
			(size 0.519938 1.4986)
			(layers "F.Cu" "F.Mask" "F.Paste")
			(net "GND")
		)
		(pad "G1" thru_hole oval
			(at 0 -68.97497)
			(size 2.8194 1.5748)
			(drill oval 2.4384 1.1938)
			(layers "*.Cu" "*.Mask")
			(remove_unused_layers no)
			(net "GND")
			(clearance 0.127)
			(thermal_gap 0.127)
		)
		(pad "G2" thru_hole oval
			(at 0 3.875024)
			(size 2.8194 1.5748)
			(drill oval 2.4384 1.1938)
			(layers "*.Cu" "*.Mask")
			(remove_unused_layers no)
			(net "GND")
			(clearance 0.127)
			(thermal_gap 0.127)
		)
		(pad "G3" thru_hole oval
			(at 0 68.97497)
			(size 2.8194 1.5748)
			(drill oval 2.4384 1.1938)
			(layers "*.Cu" "*.Mask")
			(remove_unused_layers no)
			(net "GND")
			(clearance 0.127)
			(thermal_gap 0.127)
		)
	)
)
